(kicad_pcb
	(version 20260206)
	(generator "pcbnew")
	(generator_version "10.0")
	(general
		(thickness 1.6)
		(legacy_teardrops no)
	)
	(paper "A4")
	(title_block
		(title "04192023_DAF0TMB3IC0_F0TG_MB_C_brd_V02_OCP.brd")
		(comment 1 "Grand Teton / footprint 2783 of 8354 (U26), pads 4561-4671 of 6102")
	)
	(layers
		(0 "F.Cu" signal "TOP")
		(4 "In1.Cu" signal "GND")
		(6 "In2.Cu" signal "IN1")
		(8 "In3.Cu" signal "GND1")
		(10 "In4.Cu" signal "IN2")
		(12 "In5.Cu" signal "GND2")
		(14 "In6.Cu" signal "IN3")
		(16 "In7.Cu" signal "GND3")
		(18 "In8.Cu" signal "VCC")
		(20 "In9.Cu" signal "VCC1")
		(22 "In10.Cu" signal "GND4")
		(24 "In11.Cu" signal "IN4")
		(26 "In12.Cu" signal "GND5")
		(28 "In13.Cu" signal "IN5")
		(30 "In14.Cu" signal "GND6")
		(32 "In15.Cu" signal "IN6")
		(34 "In16.Cu" signal "GND7")
		(2 "B.Cu" signal "BOTTOM")
		(9 "F.Adhes" user "F.Adhesive")
		(11 "B.Adhes" user "B.Adhesive")
		(13 "F.Paste" user "Package Geometry/Pastemask Top")
		(15 "B.Paste" user "Package Geometry/Pastemask Bottom")
		(5 "F.SilkS" user "Ref Des/Silkscreen Top")
		(7 "B.SilkS" user "Ref Des/Silkscreen Bottom")
		(1 "F.Mask" user "Board Geometry/Soldermask Top")
		(3 "B.Mask" user "Board Geometry/Soldermask Bottom")
		(17 "Dwgs.User" user "User.Drawings")
		(19 "Cmts.User" user "User.Comments")
		(21 "Eco1.User" user "User.Eco1")
		(23 "Eco2.User" user "User.Eco2")
		(25 "Edge.Cuts" user "Board Geometry/Outline")
		(27 "Margin" user)
		(31 "F.CrtYd" user "Package Geometry/Place Bound Top")
		(29 "B.CrtYd" user "Package Geometry/Place Bound Bottom")
		(35 "F.Fab" user "Ref Des/Assembly Top")
		(33 "B.Fab" user "Ref Des/Assembly Bottom")
	)
	(footprint ""
		(layer "F.Cu")
		(at 111.927894 -258.880356 180)
		(property "Reference" "U26"
			(at -45.05579 -61.794136 0)
			(unlocked yes)
			(layer "F.SilkS")
			(effects
				(font
					(size 0.7874 0.5842)
					(thickness 0.1524)
				)
			)
		)
		(property "Value" ""
			(at 0 0 180)
			(layer "F.Fab")
			(effects
				(font
					(size 1.27 1.27)
				)
			)
		)
		(duplicate_pad_numbers_are_jumpers no)
		(pad "DD26" smd circle
			(at -11.43 32.759904 180)
			(size 0.450088 0.450088)
			(layers "F.Cu" "F.Mask" "F.Paste")
			(net "GND")
		)
		(pad "DD27" smd circle
			(at -10.489946 32.759904 180)
			(size 0.450088 0.450088)
			(layers "F.Cu" "F.Mask" "F.Paste")
			(net "GND")
		)
		(pad "DD28" smd circle
			(at -9.549892 32.759904 180)
			(size 0.450088 0.450088)
			(layers "F.Cu" "F.Mask" "F.Paste")
			(net "PVDDCR_CPU1_P1")
		)
		(pad "DD29" smd circle
			(at -8.610092 32.759904 180)
			(size 0.450088 0.450088)
			(layers "F.Cu" "F.Mask" "F.Paste")
			(net "GND")
		)
		(pad "DD30" smd circle
			(at -7.670038 32.759904 180)
			(size 0.450088 0.450088)
			(layers "F.Cu" "F.Mask" "F.Paste")
			(net "GND")
		)
		(pad "DD31" smd circle
			(at -6.729984 32.759904 180)
			(size 0.450088 0.450088)
			(layers "F.Cu" "F.Mask" "F.Paste")
			(net "PVDDCR_CPU1_P1")
		)
		(pad "DD32" smd circle
			(at -5.78993 32.759904 180)
			(size 0.450088 0.450088)
			(layers "F.Cu" "F.Mask" "F.Paste")
			(net "GND")
		)
		(pad "DD33" smd circle
			(at -4.849876 32.759904 180)
			(size 0.450088 0.450088)
			(layers "F.Cu" "F.Mask" "F.Paste")
			(net "GND")
		)
		(pad "DD34" smd circle
			(at -3.910076 32.759904 180)
			(size 0.450088 0.450088)
			(layers "F.Cu" "F.Mask" "F.Paste")
			(net "PVDDCR_CPU1_P1")
		)
		(pad "DD35" smd circle
			(at -2.970022 32.759904 180)
			(size 0.450088 0.450088)
			(layers "F.Cu" "F.Mask" "F.Paste")
			(net "GND")
		)
		(pad "DD36" smd circle
			(at -2.029968 32.759904 180)
			(size 0.450088 0.450088)
			(layers "F.Cu" "F.Mask" "F.Paste")
			(net "GND")
		)
		(pad "DD37" smd circle
			(at -1.089914 32.759904 180)
			(size 0.450088 0.450088)
			(layers "F.Cu" "F.Mask" "F.Paste")
			(net "GND")
		)
		(pad "DD39" smd circle
			(at 0.78994 32.759904 180)
			(size 0.450088 0.450088)
			(layers "F.Cu" "F.Mask" "F.Paste")
			(net "GND")
		)
		(pad "DD40" smd circle
			(at 1.729994 32.759904 180)
			(size 0.450088 0.450088)
			(layers "F.Cu" "F.Mask" "F.Paste")
			(net "GND")
		)
		(pad "DD41" smd circle
			(at 2.670048 32.759904 180)
			(size 0.450088 0.450088)
			(layers "F.Cu" "F.Mask" "F.Paste")
			(net "GND")
		)
		(pad "DD42" smd circle
			(at 3.610102 32.759904 180)
			(size 0.450088 0.450088)
			(layers "F.Cu" "F.Mask" "F.Paste")
			(net "PVDDCR_CPU1_P1")
		)
		(pad "DD43" smd circle
			(at 4.549902 32.759904 180)
			(size 0.450088 0.450088)
			(layers "F.Cu" "F.Mask" "F.Paste")
			(net "GND")
		)
		(pad "DD44" smd circle
			(at 5.489956 32.759904 180)
			(size 0.450088 0.450088)
			(layers "F.Cu" "F.Mask" "F.Paste")
			(net "GND")
		)
		(pad "DD45" smd circle
			(at 6.43001 32.759904 180)
			(size 0.450088 0.450088)
			(layers "F.Cu" "F.Mask" "F.Paste")
			(net "PVDDCR_CPU1_P1")
		)
		(pad "DD46" smd circle
			(at 7.370064 32.759904 180)
			(size 0.450088 0.450088)
			(layers "F.Cu" "F.Mask" "F.Paste")
			(net "GND")
		)
		(pad "DD47" smd circle
			(at 8.310118 32.759904 180)
			(size 0.450088 0.450088)
			(layers "F.Cu" "F.Mask" "F.Paste")
			(net "GND")
		)
		(pad "DD48" smd circle
			(at 9.249918 32.759904 180)
			(size 0.450088 0.450088)
			(layers "F.Cu" "F.Mask" "F.Paste")
			(net "PVDDCR_CPU1_P1")
		)
		(pad "DD49" smd circle
			(at 10.189972 32.759904 180)
			(size 0.450088 0.450088)
			(layers "F.Cu" "F.Mask" "F.Paste")
			(net "GND")
		)
		(pad "DD50" smd circle
			(at 11.130026 32.759904 180)
			(size 0.450088 0.450088)
			(layers "F.Cu" "F.Mask" "F.Paste")
			(net "GND")
		)
		(pad "DD51" smd circle
			(at 12.07008 32.759904 180)
			(size 0.450088 0.450088)
			(layers "F.Cu" "F.Mask" "F.Paste")
			(net "PVDDCR_CPU1_P1")
		)
		(pad "DD52" smd circle
			(at 13.00988 32.759904 180)
			(size 0.450088 0.450088)
			(layers "F.Cu" "F.Mask" "F.Paste")
			(net "GND")
		)
		(pad "DD53" smd circle
			(at 13.949934 32.759904 180)
			(size 0.450088 0.450088)
			(layers "F.Cu" "F.Mask" "F.Paste")
			(net "GND")
		)
		(pad "DD54" smd circle
			(at 14.889988 32.759904 180)
			(size 0.450088 0.450088)
			(layers "F.Cu" "F.Mask" "F.Paste")
			(net "PVDDCR_CPU1_P1")
		)
		(pad "DD55" smd circle
			(at 15.830042 32.759904 180)
			(size 0.450088 0.450088)
			(layers "F.Cu" "F.Mask" "F.Paste")
			(net "M_C_CPU1_SB_DQS_DP<8>")
		)
		(pad "DD56" smd circle
			(at 16.770096 32.759904 180)
			(size 0.450088 0.450088)
			(layers "F.Cu" "F.Mask" "F.Paste")
			(net "M_C_CPU1_SB_DQ<28>")
		)
		(pad "DD57" smd circle
			(at 17.709896 32.759904 180)
			(size 0.450088 0.450088)
			(layers "F.Cu" "F.Mask" "F.Paste")
			(net "GND")
		)
		(pad "DD58" smd circle
			(at 18.64995 32.759904 180)
			(size 0.450088 0.450088)
			(layers "F.Cu" "F.Mask" "F.Paste")
			(net "M_D_CPU1_SB_DQS_DP<8>")
		)
		(pad "DD59" smd circle
			(at 19.590004 32.759904 180)
			(size 0.450088 0.450088)
			(layers "F.Cu" "F.Mask" "F.Paste")
			(net "GND")
		)
		(pad "DD60" smd circle
			(at 20.530058 32.759904 180)
			(size 0.450088 0.450088)
			(layers "F.Cu" "F.Mask" "F.Paste")
			(net "M_D_CPU1_SB_DQ<28>")
		)
		(pad "DD61" smd circle
			(at 21.470112 32.759904 180)
			(size 0.450088 0.450088)
			(layers "F.Cu" "F.Mask" "F.Paste")
			(net "GND")
		)
		(pad "DD62" smd circle
			(at 22.409912 32.759904 180)
			(size 0.450088 0.450088)
			(layers "F.Cu" "F.Mask" "F.Paste")
			(net "M_B_CPU1_SB_DQS_DP<8>")
		)
		(pad "DD63" smd circle
			(at 23.349966 32.759904 180)
			(size 0.450088 0.450088)
			(layers "F.Cu" "F.Mask" "F.Paste")
			(net "M_B_CPU1_SB_DQ<28>")
		)
		(pad "DD64" smd circle
			(at 24.29002 32.759904 180)
			(size 0.450088 0.450088)
			(layers "F.Cu" "F.Mask" "F.Paste")
			(net "GND")
		)
		(pad "DD65" smd circle
			(at 25.230074 32.759904 180)
			(size 0.450088 0.450088)
			(layers "F.Cu" "F.Mask" "F.Paste")
			(net "M_F_CPU1_SB_DQS_DP<8>")
		)
		(pad "DD66" smd circle
			(at 26.170128 32.759904 180)
			(size 0.450088 0.450088)
			(layers "F.Cu" "F.Mask" "F.Paste")
			(net "GND")
		)
		(pad "DD67" smd circle
			(at 27.109928 32.759904 180)
			(size 0.450088 0.450088)
			(layers "F.Cu" "F.Mask" "F.Paste")
			(net "M_F_CPU1_SB_DQ<28>")
		)
		(pad "DD68" smd circle
			(at 28.049982 32.759904 180)
			(size 0.450088 0.450088)
			(layers "F.Cu" "F.Mask" "F.Paste")
			(net "GND")
		)
		(pad "DD69" smd circle
			(at 28.990036 32.759904 180)
			(size 0.450088 0.450088)
			(layers "F.Cu" "F.Mask" "F.Paste")
			(net "M_E_CPU1_SB_DQS_DP<8>")
		)
		(pad "DD70" smd circle
			(at 29.93009 32.759904 180)
			(size 0.450088 0.450088)
			(layers "F.Cu" "F.Mask" "F.Paste")
			(net "M_E_CPU1_SB_DQ<28>")
		)
		(pad "DD71" smd circle
			(at 30.86989 32.759904 180)
			(size 0.450088 0.450088)
			(layers "F.Cu" "F.Mask" "F.Paste")
			(net "GND")
		)
		(pad "DD72" smd circle
			(at 31.809944 32.759904 180)
			(size 0.450088 0.450088)
			(layers "F.Cu" "F.Mask" "F.Paste")
			(net "M_A_CPU1_SB_DQS_DP<8>")
		)
		(pad "DD73" smd circle
			(at 32.749998 32.759904 180)
			(size 0.450088 0.450088)
			(layers "F.Cu" "F.Mask" "F.Paste")
			(net "GND")
		)
		(pad "DD74" smd circle
			(at 33.690052 32.759904 180)
			(size 0.450088 0.450088)
			(layers "F.Cu" "F.Mask" "F.Paste")
			(net "M_A_CPU1_SB_DQ<28>")
		)
		(pad "DE1" smd circle
			(at -34.459926 33.56991 180)
			(size 0.450088 0.450088)
			(layers "F.Cu" "F.Mask" "F.Paste")
			(net "GND")
		)
		(pad "DE2" smd circle
			(at -33.519872 33.56991 180)
			(size 0.450088 0.450088)
			(layers "F.Cu" "F.Mask" "F.Paste")
			(net "M_G_CPU1_SB_DQ<30>")
		)
		(pad "DE3" smd circle
			(at -32.580072 33.56991 180)
			(size 0.450088 0.450088)
			(layers "F.Cu" "F.Mask" "F.Paste")
			(net "M_G_CPU1_SB_DQ<29>")
		)
		(pad "DE4" smd circle
			(at -31.640018 33.56991 180)
			(size 0.450088 0.450088)
			(layers "F.Cu" "F.Mask" "F.Paste")
			(net "PVDD11_S3_P1")
		)
		(pad "DE5" smd circle
			(at -30.699964 33.56991 180)
			(size 0.450088 0.450088)
			(layers "F.Cu" "F.Mask" "F.Paste")
			(net "M_K_CPU1_SB_DQ<30>")
		)
		(pad "DE6" smd circle
			(at -29.75991 33.56991 180)
			(size 0.450088 0.450088)
			(layers "F.Cu" "F.Mask" "F.Paste")
			(net "GND")
		)
		(pad "DE7" smd circle
			(at -28.82011 33.56991 180)
			(size 0.450088 0.450088)
			(layers "F.Cu" "F.Mask" "F.Paste")
			(net "M_K_CPU1_SB_DQ<29>")
		)
		(pad "DE8" smd circle
			(at -27.880056 33.56991 180)
			(size 0.450088 0.450088)
			(layers "F.Cu" "F.Mask" "F.Paste")
			(net "GND")
		)
		(pad "DE9" smd circle
			(at -26.940002 33.56991 180)
			(size 0.450088 0.450088)
			(layers "F.Cu" "F.Mask" "F.Paste")
			(net "M_L_CPU1_SB_DQ<30>")
		)
		(pad "DE10" smd circle
			(at -25.999948 33.56991 180)
			(size 0.450088 0.450088)
			(layers "F.Cu" "F.Mask" "F.Paste")
			(net "M_L_CPU1_SB_DQ<29>")
		)
		(pad "DE11" smd circle
			(at -25.059894 33.56991 180)
			(size 0.450088 0.450088)
			(layers "F.Cu" "F.Mask" "F.Paste")
			(net "PVDD11_S3_P1")
		)
		(pad "DE12" smd circle
			(at -24.120094 33.56991 180)
			(size 0.450088 0.450088)
			(layers "F.Cu" "F.Mask" "F.Paste")
			(net "M_H_CPU1_SB_DQ<30>")
		)
		(pad "DE13" smd circle
			(at -23.18004 33.56991 180)
			(size 0.450088 0.450088)
			(layers "F.Cu" "F.Mask" "F.Paste")
			(net "GND")
		)
		(pad "DE14" smd circle
			(at -22.239986 33.56991 180)
			(size 0.450088 0.450088)
			(layers "F.Cu" "F.Mask" "F.Paste")
			(net "M_H_CPU1_SB_DQ<29>")
		)
		(pad "DE15" smd circle
			(at -21.299932 33.56991 180)
			(size 0.450088 0.450088)
			(layers "F.Cu" "F.Mask" "F.Paste")
			(net "GND")
		)
		(pad "DE16" smd circle
			(at -20.359878 33.56991 180)
			(size 0.450088 0.450088)
			(layers "F.Cu" "F.Mask" "F.Paste")
			(net "M_J_CPU1_SB_DQ<30>")
		)
		(pad "DE17" smd circle
			(at -19.420078 33.56991 180)
			(size 0.450088 0.450088)
			(layers "F.Cu" "F.Mask" "F.Paste")
			(net "M_J_CPU1_SB_DQ<29>")
		)
		(pad "DE18" smd circle
			(at -18.480024 33.56991 180)
			(size 0.450088 0.450088)
			(layers "F.Cu" "F.Mask" "F.Paste")
			(net "PVDD11_S3_P1")
		)
		(pad "DE19" smd circle
			(at -17.53997 33.56991 180)
			(size 0.450088 0.450088)
			(layers "F.Cu" "F.Mask" "F.Paste")
			(net "M_I_CPU1_SB_DQ<30>")
		)
		(pad "DE20" smd circle
			(at -16.599916 33.56991 180)
			(size 0.450088 0.450088)
			(layers "F.Cu" "F.Mask" "F.Paste")
			(net "GND")
		)
		(pad "DE21" smd circle
			(at -15.660116 33.56991 180)
			(size 0.450088 0.450088)
			(layers "F.Cu" "F.Mask" "F.Paste")
			(net "M_I_CPU1_SB_DQ<29>")
		)
		(pad "DE22" smd circle
			(at -14.720062 33.56991 180)
			(size 0.450088 0.450088)
			(layers "F.Cu" "F.Mask" "F.Paste")
			(net "PVDDCR_CPU1_P1")
		)
		(pad "DE23" smd circle
			(at -13.780008 33.56991 180)
			(size 0.450088 0.450088)
			(layers "F.Cu" "F.Mask" "F.Paste")
			(net "GND")
		)
		(pad "DE24" smd circle
			(at -12.839954 33.56991 180)
			(size 0.450088 0.450088)
			(layers "F.Cu" "F.Mask" "F.Paste")
			(net "Net_2110")
		)
		(pad "DE25" smd circle
			(at -11.8999 33.56991 180)
			(size 0.450088 0.450088)
			(layers "F.Cu" "F.Mask" "F.Paste")
			(net "PVDDCR_CPU1_P1")
		)
		(pad "DE26" smd circle
			(at -10.9601 33.56991 180)
			(size 0.450088 0.450088)
			(layers "F.Cu" "F.Mask" "F.Paste")
			(net "GND")
		)
		(pad "DE27" smd circle
			(at -10.020046 33.56991 180)
			(size 0.450088 0.450088)
			(layers "F.Cu" "F.Mask" "F.Paste")
			(net "Net_2117")
		)
		(pad "DE28" smd circle
			(at -9.079992 33.56991 180)
			(size 0.450088 0.450088)
			(layers "F.Cu" "F.Mask" "F.Paste")
			(net "PVDDCR_CPU1_P1")
		)
		(pad "DE29" smd circle
			(at -8.139938 33.56991 180)
			(size 0.450088 0.450088)
			(layers "F.Cu" "F.Mask" "F.Paste")
			(net "GND")
		)
		(pad "DE30" smd circle
			(at -7.199884 33.56991 180)
			(size 0.450088 0.450088)
			(layers "F.Cu" "F.Mask" "F.Paste")
			(net "Net_2076")
		)
		(pad "DE31" smd circle
			(at -6.260084 33.56991 180)
			(size 0.450088 0.450088)
			(layers "F.Cu" "F.Mask" "F.Paste")
			(net "PVDDCR_CPU1_P1")
		)
		(pad "DE32" smd circle
			(at -5.32003 33.56991 180)
			(size 0.450088 0.450088)
			(layers "F.Cu" "F.Mask" "F.Paste")
			(net "TP_SLOT2_BUF_SKU_ID1")
		)
		(pad "DE33" smd circle
			(at -4.379976 33.56991 180)
			(size 0.450088 0.450088)
			(layers "F.Cu" "F.Mask" "F.Paste")
			(net "GND")
		)
		(pad "DE34" smd circle
			(at -3.439922 33.56991 180)
			(size 0.450088 0.450088)
			(layers "F.Cu" "F.Mask" "F.Paste")
			(net "PVDDCR_CPU1_P1")
		)
		(pad "DE35" smd circle
			(at -2.500122 33.56991 180)
			(size 0.450088 0.450088)
			(layers "F.Cu" "F.Mask" "F.Paste")
			(net "PVDDCR_CPU1_P1")
		)
		(pad "DE36" smd circle
			(at -1.560068 33.56991 180)
			(size 0.450088 0.450088)
			(layers "F.Cu" "F.Mask" "F.Paste")
			(net "CPU1_SPD_HOST_CTRL_R_N")
		)
		(pad "DE40" smd circle
			(at 1.260094 33.56991 180)
			(size 0.450088 0.450088)
			(layers "F.Cu" "F.Mask" "F.Paste")
			(net "FM_BMC_READY_N")
		)
		(pad "DE41" smd circle
			(at 2.199894 33.56991 180)
			(size 0.450088 0.450088)
			(layers "F.Cu" "F.Mask" "F.Paste")
			(net "PVDDCR_CPU1_P1")
		)
		(pad "DE42" smd circle
			(at 3.139948 33.56991 180)
			(size 0.450088 0.450088)
			(layers "F.Cu" "F.Mask" "F.Paste")
			(net "PVDDCR_CPU1_P1")
		)
		(pad "DE43" smd circle
			(at 4.080002 33.56991 180)
			(size 0.450088 0.450088)
			(layers "F.Cu" "F.Mask" "F.Paste")
			(net "P3E_CPU1_P4_TX_DN<3>")
		)
		(pad "DE44" smd circle
			(at 5.020056 33.56991 180)
			(size 0.450088 0.450088)
			(layers "F.Cu" "F.Mask" "F.Paste")
			(net "P3E_CPU1_P4_TX_DP<3>")
		)
		(pad "DE45" smd circle
			(at 5.96011 33.56991 180)
			(size 0.450088 0.450088)
			(layers "F.Cu" "F.Mask" "F.Paste")
			(net "PVDDCR_CPU1_P1")
		)
		(pad "DE46" smd circle
			(at 6.89991 33.56991 180)
			(size 0.450088 0.450088)
			(layers "F.Cu" "F.Mask" "F.Paste")
			(net "P3E_CPU1_P4_TX_DN<2>")
		)
		(pad "DE47" smd circle
			(at 7.839964 33.56991 180)
			(size 0.450088 0.450088)
			(layers "F.Cu" "F.Mask" "F.Paste")
			(net "P3E_CPU1_P4_TX_DP<2>")
		)
		(pad "DE48" smd circle
			(at 8.780018 33.56991 180)
			(size 0.450088 0.450088)
			(layers "F.Cu" "F.Mask" "F.Paste")
			(net "PVDDCR_CPU1_P1")
		)
		(pad "DE49" smd circle
			(at 9.720072 33.56991 180)
			(size 0.450088 0.450088)
			(layers "F.Cu" "F.Mask" "F.Paste")
			(net "P3E_CPU1_P4_TX_DN<1>")
		)
		(pad "DE50" smd circle
			(at 10.659872 33.56991 180)
			(size 0.450088 0.450088)
			(layers "F.Cu" "F.Mask" "F.Paste")
			(net "P3E_CPU1_P4_TX_DP<1>")
		)
		(pad "DE51" smd circle
			(at 11.599926 33.56991 180)
			(size 0.450088 0.450088)
			(layers "F.Cu" "F.Mask" "F.Paste")
			(net "PVDDCR_CPU1_P1")
		)
		(pad "DE52" smd circle
			(at 12.53998 33.56991 180)
			(size 0.450088 0.450088)
			(layers "F.Cu" "F.Mask" "F.Paste")
			(net "P3E_CPU1_P4_TX_DN<0>")
		)
		(pad "DE53" smd circle
			(at 13.480034 33.56991 180)
			(size 0.450088 0.450088)
			(layers "F.Cu" "F.Mask" "F.Paste")
			(net "P3E_CPU1_P4_TX_DP<0>")
		)
		(pad "DE54" smd circle
			(at 14.420088 33.56991 180)
			(size 0.450088 0.450088)
			(layers "F.Cu" "F.Mask" "F.Paste")
			(net "PVDDCR_CPU1_P1")
		)
		(pad "DE55" smd circle
			(at 15.359888 33.56991 180)
			(size 0.450088 0.450088)
			(layers "F.Cu" "F.Mask" "F.Paste")
			(net "M_C_CPU1_SB_DQ<29>")
		)
		(pad "DE56" smd circle
			(at 16.299942 33.56991 180)
			(size 0.450088 0.450088)
			(layers "F.Cu" "F.Mask" "F.Paste")
			(net "GND")
		)
		(pad "DE57" smd circle
			(at 17.239996 33.56991 180)
			(size 0.450088 0.450088)
			(layers "F.Cu" "F.Mask" "F.Paste")
			(net "M_C_CPU1_SB_DQ<30>")
		)
		(pad "DE58" smd circle
			(at 18.18005 33.56991 180)
			(size 0.450088 0.450088)
			(layers "F.Cu" "F.Mask" "F.Paste")
			(net "PVDDIO_P1")
		)
		(pad "DE59" smd circle
			(at 19.120104 33.56991 180)
			(size 0.450088 0.450088)
			(layers "F.Cu" "F.Mask" "F.Paste")
			(net "M_D_CPU1_SB_DQ<29>")
		)
		(pad "DE60" smd circle
			(at 20.059904 33.56991 180)
			(size 0.450088 0.450088)
			(layers "F.Cu" "F.Mask" "F.Paste")
			(net "M_D_CPU1_SB_DQ<30>")
		)
		(pad "DE61" smd circle
			(at 20.999958 33.56991 180)
			(size 0.450088 0.450088)
			(layers "F.Cu" "F.Mask" "F.Paste")
			(net "GND")
		)
		(pad "DE62" smd circle
			(at 21.940012 33.56991 180)
			(size 0.450088 0.450088)
			(layers "F.Cu" "F.Mask" "F.Paste")
			(net "M_B_CPU1_SB_DQ<29>")
		)
		(pad "DE63" smd circle
			(at 22.880066 33.56991 180)
			(size 0.450088 0.450088)
			(layers "F.Cu" "F.Mask" "F.Paste")
			(net "GND")
		)
		(pad "DE64" smd circle
			(at 23.82012 33.56991 180)
			(size 0.450088 0.450088)
			(layers "F.Cu" "F.Mask" "F.Paste")
			(net "M_B_CPU1_SB_DQ<30>")
		)
		(pad "DE65" smd circle
			(at 24.75992 33.56991 180)
			(size 0.450088 0.450088)
			(layers "F.Cu" "F.Mask" "F.Paste")
			(net "PVDDIO_P1")
		)
		(pad "DE66" smd circle
			(at 25.699974 33.56991 180)
			(size 0.450088 0.450088)
			(layers "F.Cu" "F.Mask" "F.Paste")
			(net "M_F_CPU1_SB_DQ<29>")
		)
	)
)
